FILE_TYPE = CONNECTIVITY;
{Allegro Design Entry HDL 17.2-2016 S081 (4005846) 1/11/2022}
"PAGE_NUMBER" = 175;
0"NC";
1"P3V3_STBY\g";
2"GND\g";
3"GND\g";
4"P3V3_STBY\g";
5"GND\g";
6"GND\g";
7"GND\g";
8"GND\g";
9"GND\g";
10"GND\g";
11"GND\g";
12"P5V_STBY\g";
13"GND\g";
14"GND\g";
15"GND\g";
16"GND\g";
17"GND\g";
18"GND\g";
19"GND\g";
20"GND\g";
21"PVDDCR_CPU1_P0_SMB_ALERT_R";
22"PVDDCR_CPU1_P0\g";
23"SMB_SCM_6_R1_SCL";
24"SMB_CLK_PVDDCR_CPU1_P0_R";
25"SMB_SCM_6_R1_SDA";
26"PVDDCR_CPU1_P0_VINSEN";
27"GND\g";
28"PVDDCR_CPU1_P0_VMON";
29"PWRGD_PVDDIO_P0_R";
30"PWRGD_PVDDIO_P0";
31"GND\g";
32"PVDDIO_P0_EN_R";
33"PVDDCR_CPU1_P0_IMON5";
34"PVDDIO_P0_EN";
35"PVDDCR_CPU1_P0_SMB_ALERT";
36"SVID_PVDDCR_CPU1_P0_SVD_R";
37"SVID_PVDDCR_CPU1_P0_SVC_R";
38"PVDDCR_CPU1_P0_EN_R";
39"PWRGD_PVDDCR_CPU1_P0_R";
40"PVDDCR_CPU1_P0_IMON2";
41"SVID_PVDDCR_CPU1_P0_SVTI_R";
42"PVDDIO_P0_PWM4";
43"NC_PVDDCR_CPU1_P0_IMON8";
44"PVDDIO_P0_IMON4";
45"NC_PVDDCR_CPU1_P0_PWM7";
46"SVID_PVDDCR_CPU1_P0_SVTO_R";
47"SMB_DIO_PVDDCR_CPU1_P0_R";
48"VSENSE_PVDDIO_P0_VSEN1";
49"PVDDIO_P0_PWM3";
50"PVDDCR_CPU1_P0_PWM2";
51"PVDDCR_CPU1_P0_IMON1";
52"PVDDCR_CPU1_P0_PWM1";
53"PVDDCR_CPU1_P0_IMON3";
54"GND\g";
55"P3V3_STBY\g";
56"PVDD18_S5_P0\g";
57"PVDDCR_CPU1_P0_RESET_N";
58"PVDD18_S5_P0\g";
59"PVDDCR_CPU1_P0_EN1_ADDR_CFG";
60"PVDDCR_CPU1_P0_RESET_N_R";
61"PVDDIO_P0_TEMP1";
62"PVDDCR_CPU1_P0_PWM4";
63"PVDDCR_CPU1_P0_OCP_N";
64"PVDDCR_CPU1_P0_OCP_N_R";
65"PVDDIO_P0_EN_G";
66"SVID_PVDDCR_CPU1_P0_SVTI";
67"GND\g";
68"SVID_PVDDCR_CPU1_P0_SVTO";
69"PVDD18_S5_P0\g";
70"FM_PVDDCR_CPU1_P0_EN";
71"PWRGD_PVDDCR_CPU1_P0";
72"P12V_STBY\g";
73"VSENSE_PVDDCR_CPU1_P0_VSEN0";
74"PVDDCR_CPU1_P0_VCCS";
75"PVDDCR_CPU1_P0_VCC";
76"PVDDCR_CPU1_P0_TEMP0";
77"PVDDIO_P0_PWM1";
78"PVDDIO_P0_IMON1";
79"PVDDIO_P0_PWM2";
80"PVDDIO_P0_IMON2";
81"PVDDCR_CPU1_P0_PWM3";
82"PVDDCR_CPU1_P0_IMON4";
83"PVDDCR_CPU1_P0_PWM5";
84"PVDDCR_CPU1_P0_PWM6";
85"PVDDCR_CPU1_P0_IMON6";
86"P3V3_STBY\g";
87"PVDDIO_P0_IMON3";
88"NC_PVDDCR_CPU1_P0_IMON7";
89"NC_PVDDCR_CPU1_P0_PWM8";
90"PVDDIO_P0\g";
91"VSENSE_PVDDIO_P0_DP";
92"VSENSE_VSS_SENSE_C_P0";
93"VSENSE_PVDDCR_CPU1_P0_DP";
94"VSENSE_VSS_SENSE_B_P0";
%"Q_RES"
"1","(-8575,1025)","0","pure_quanta","I219";
;
LOCATION"PR53"
$SEC"1"
CDS_SEC"1"
MATERIAL"CHIP"
VALUE"40.2K"
TOLERANCE"1%"
PACK_TYPE"0402LF"
PART_NUMBER"TMP_QCS34022FB15"
WATTAGE"1/16W"
CDS_LIB"pure_quanta";
"B"
$PN"2"28;
"A"
$PN"1"12;
%"Q_RES"
"1","(-7350,850)","0","pure_quanta","I220";
;
LOCATION"PR74"
$SEC"1"
CDS_SEC"1"
WATTAGE"1/16W"
MATERIAL"CHIP"
TOLERANCE"5%"
VALUE"0"
PART_NUMBER"CS00002JB38"
PACK_TYPE"0402LF"
CDS_LIB"pure_quanta";
"B"
$PN"2"26;
"A"
$PN"1"72;
%"VCC_CORE"
"1","(-7525,925)","0","pure_quanta_power","I221";
;
HDL_POWER"P12V_STBY"
CDS_LIB"pure_quanta_power";
"A"72;
%"VCC_CORE"
"1","(-8450,1375)","0","pure_quanta_power","I222";
;
HDL_POWER"P3V3_STBY"
CDS_LIB"pure_quanta_power";
"A"1;
%"Q_RES"
"1","(-7975,1125)","0","pure_quanta","I223";
;
LOCATION"PR66"
$SEC"1"
CDS_SEC"1"
WATTAGE"1/16W"
MATERIAL"CHIP"
PACK_TYPE"0402LF"
PART_NUMBER"CS00002JB38"
VALUE"0"
TOLERANCE"5%"
CDS_LIB"pure_quanta";
"B"
$PN"2"29;
"A"
$PN"1"30;
%"Q_RES"
"1","(-7975,1275)","0","pure_quanta","I224";
;
LOCATION"PR65"
$SEC"1"
CDS_SEC"1"
PACK_TYPE"0402LF"
WATTAGE"1/16W"
MATERIAL"CHIP"
TOLERANCE"1%"
VALUE"1K"
PART_NUMBER"TMP_QCS21002FB24"
CDS_LIB"pure_quanta";
"B"
$PN"2"29;
"A"
$PN"1"1;
%"UNIVERSAL_GND"
"1","(-7800,550)","0","pure_quanta_power","I226";
;
CDS_LIB"pure_quanta_power"
HDL_POWER"GND";
"A"31;
%"Q_RES"
"2","(-8250,850)","0","pure_quanta","I227";
;
LOCATION"PR54"
$SEC"1"
CDS_SEC"1"
PART_NUMBER"TMP_QCS31002FB26"
PACK_TYPE"0402LF"
WATTAGE"1/16W"
MATERIAL"CHIP"
TOLERANCE"1%"
VALUE"10K"
CDS_LIB"pure_quanta";
"A"
$PN"1"28;
"B"
$PN"2"31;
%"Q_CAP"
"1","(-7800,875)","0","pure_quanta","I228";
;
LOCATION"PC67"
$SEC"1"
CDS_SEC"1"
MATERIAL"X7R"
TOLERANCE"10%"
VALUE"0.1UF"
PART_NUMBER"CH4104K1B00"
VOLTAGE"25V"
PACK_TYPE"0402"
CDS_LIB"pure_quanta";
"B"
$PN"2"31;
"A"
$PN"1"28;
%"Q_CAP"
"2","(-7175,1275)","0","pure_quanta","I230";
;
LOCATION"PC72"
$SEC"1"
CDS_SEC"1"
PART_NUMBER"TMP_QCH21006JB10"
MATERIAL"EMPTY"
TOLERANCE"5%"
VALUE"1000PF"
VOLTAGE"50V"
PACK_TYPE"0402"
CDS_LIB"pure_quanta";
"A"
$PN"1"29;
"B"
$PN"2"6;
%"Q_RES"
"1","(-8750,2750)","0","pure_quanta","I233";
;
LOCATION"PR50"
$SEC"1"
CDS_SEC"1"
MATERIAL"CHIP"
PART_NUMBER"CS04992FB31"
PACK_TYPE"0402LF"
WATTAGE"1/16W"
VALUE"49.9"
TOLERANCE"1%"
CDS_LIB"pure_quanta";
"B"
$PN"2"2;
"A"
$PN"1"94;
%"UNIVERSAL_GND"
"1","(-8225,2650)","0","pure_quanta_power","I238";
;
CDS_LIB"pure_quanta_power"
HDL_POWER"GND";
"A"2;
%"Q_RES"
"1","(-8700,3425)","0","pure_quanta","I239";
;
LOCATION"PR52"
$SEC"1"
CDS_SEC"1"
WATTAGE"1/16W"
MATERIAL"CHIP"
PART_NUMBER"CS04992FB31"
PACK_TYPE"0402LF"
VALUE"49.9"
TOLERANCE"1%"
CDS_LIB"pure_quanta";
"B"
$PN"2"90;
"A"
$PN"1"91;
%"Q_RES"
"1","(-8750,3850)","0","pure_quanta","I240";
;
LOCATION"PR49"
$SEC"1"
CDS_SEC"1"
WATTAGE"1/16W"
MATERIAL"CHIP"
PART_NUMBER"CS04992FB31"
PACK_TYPE"0402LF"
VALUE"49.9"
TOLERANCE"1%"
CDS_LIB"pure_quanta";
"B"
$PN"2"3;
"A"
$PN"1"92;
%"VCC_CORE"
"1","(-8200,3575)","0","pure_quanta_power","I241";
;
HDL_POWER"PVDDIO_P0"
CDS_LIB"pure_quanta_power";
"A"90;
%"UNIVERSAL_GND"
"1","(-8225,3750)","0","pure_quanta_power","I242";
;
CDS_LIB"pure_quanta_power"
HDL_POWER"GND";
"A"3;
%"Q_CAP"
"1","(-7225,3100)","0","pure_quanta","I245";
;
LOCATION"PC71"
$SEC"1"
CDS_SEC"1"
MATERIAL"X7R"
TOLERANCE"10%"
VALUE"3300PF"
PART_NUMBER"TMP_QCH2336K1B12"
VOLTAGE"50V"
PACK_TYPE"0402"
CDS_LIB"pure_quanta";
"B"
$PN"2"94;
"A"
$PN"1"48;
%"Q_RES"
"1","(-7675,3275)","0","pure_quanta","I246";
;
LOCATION"PR69"
$SEC"1"
CDS_SEC"1"
WATTAGE"1/16W"
MATERIAL"CHIP"
TOLERANCE"5%"
VALUE"10"
PART_NUMBER"TMP_QCS01002JB22"
PACK_TYPE"0402LF"
CDS_LIB"pure_quanta";
"B"
$PN"2"48;
"A"
$PN"1"91;
%"Q_CAP"
"1","(-7275,4200)","0","pure_quanta","I247";
;
LOCATION"PC68"
$SEC"1"
CDS_SEC"1"
MATERIAL"X7R"
TOLERANCE"10%"
VALUE"3300PF"
PART_NUMBER"TMP_QCH2336K1B12"
VOLTAGE"50V"
PACK_TYPE"0402"
CDS_LIB"pure_quanta";
"B"
$PN"2"92;
"A"
$PN"1"73;
%"Q_RES"
"1","(-8700,4525)","0","pure_quanta","I261";
;
LOCATION"PR51"
$SEC"1"
CDS_SEC"1"
PACK_TYPE"0402LF"
PART_NUMBER"CS04992FB31"
WATTAGE"1/16W"
MATERIAL"CHIP"
VALUE"49.9"
TOLERANCE"1%"
CDS_LIB"pure_quanta";
"B"
$PN"2"22;
"A"
$PN"1"93;
%"VCC_CORE"
"1","(-8025,4675)","0","pure_quanta_power","I264";
;
HDL_POWER"PVDDCR_CPU1_P0"
CDS_LIB"pure_quanta_power";
"A"22;
%"Q_RES"
"1","(-7725,4375)","0","pure_quanta","I271";
;
LOCATION"PR68"
$SEC"1"
CDS_SEC"1"
WATTAGE"1/16W"
MATERIAL"CHIP"
TOLERANCE"5%"
VALUE"10"
PART_NUMBER"TMP_QCS01002JB22"
PACK_TYPE"0402LF"
CDS_LIB"pure_quanta";
"B"
$PN"2"73;
"A"
$PN"1"93;
%"Q_RES"
"1","(-7350,5225)","0","pure_quanta","I273";
;
LOCATION"PR71"
$SEC"1"
CDS_SEC"1"
PART_NUMBER"CS00002JB38"
MATERIAL"CHIP"
TOLERANCE"5%"
PACK_TYPE"0402LF"
VALUE"0"
WATTAGE"1/16W"
CDS_LIB"pure_quanta";
"B"
$PN"2"24;
"A"
$PN"1"23;
%"Q_CAP"
"2","(-7250,6100)","0","pure_quanta","I274";
;
LOCATION"PC69"
$SEC"1"
CDS_SEC"1"
TOLERANCE"5%"
MATERIAL"X7R"
VALUE"1000PF"
PART_NUMBER"TMP_QCH21006JB10"
VOLTAGE"50V"
PACK_TYPE"0402"
CDS_LIB"pure_quanta";
"A"
$PN"1"38;
"B"
$PN"2"8;
%"Q_RES"
"1","(-8075,6225)","0","pure_quanta","I275";
;
LOCATION"PR58"
$SEC"1"
CDS_SEC"1"
WATTAGE"1/16W"
MATERIAL"CHIP"
TOLERANCE"5%"
VALUE"0"
PART_NUMBER"CS00002JB38"
PACK_TYPE"0402LF"
CDS_LIB"pure_quanta";
"B"
$PN"2"38;
"A"
$PN"1"70;
%"VCC_CORE"
"1","(-8500,6625)","0","pure_quanta_power","I276";
;
HDL_POWER"P3V3_STBY"
CDS_LIB"pure_quanta_power";
"A"4;
%"Q_RES"
"1","(-8075,6375)","0","pure_quanta","I277";
;
LOCATION"PR57"
$SEC"1"
CDS_SEC"1"
WATTAGE"1/16W"
MATERIAL"CHIP"
TOLERANCE"5%"
VALUE"0"
PART_NUMBER"CS00002JB38"
PACK_TYPE"0402LF"
CDS_LIB"pure_quanta";
"B"
$PN"2"39;
"A"
$PN"1"71;
%"Q_RES"
"1","(-8075,6525)","0","pure_quanta","I278";
;
LOCATION"PR56"
$SEC"1"
CDS_SEC"1"
WATTAGE"1/16W"
MATERIAL"CHIP"
TOLERANCE"1%"
VALUE"1K"
PART_NUMBER"TMP_QCS21002FB24"
PACK_TYPE"0402LF"
CDS_LIB"pure_quanta";
"B"
$PN"2"39;
"A"
$PN"1"4;
%"Q_CAP"
"2","(-7225,6525)","0","pure_quanta","I279";
;
LOCATION"PC70"
$SEC"1"
CDS_SEC"1"
PART_NUMBER"TMP_QCH21006JB10"
MATERIAL"EMPTY"
TOLERANCE"5%"
VALUE"1000PF"
VOLTAGE"50V"
PACK_TYPE"0402"
CDS_LIB"pure_quanta";
"A"
$PN"1"39;
"B"
$PN"2"9;
%"UNIVERSAL_GND"
"1","(-6675,450)","0","pure_quanta_power","I280";
;
CDS_LIB"pure_quanta_power"
HDL_POWER"GND";
"A"5;
%"Q_CAP"
"1","(-6675,650)","0","pure_quanta","I281";
;
LOCATION"PC74"
$SEC"1"
CDS_SEC"1"
PART_NUMBER"CH4104K1B00"
VALUE"0.1UF"
VOLTAGE"25V"
PACK_TYPE"0402"
MATERIAL"X7R"
TOLERANCE"10%"
CDS_LIB"pure_quanta";
"B"
$PN"2"5;
"A"
$PN"1"26;
%"UNIVERSAL_GND"
"1","(-6450,700)","0","pure_quanta_power","I282";
;
CDS_LIB"pure_quanta_power"
HDL_POWER"GND";
"A"27;
%"UNIVERSAL_GND"
"1","(-6475,1275)","1","pure_quanta_power","I284";
;
CDS_LIB"pure_quanta_power"
HDL_POWER"GND";
"A"6;
%"UNIVERSAL_GND"
"1","(-4350,750)","0","pure_quanta_power","I285";
;
CDS_LIB"pure_quanta_power"
HDL_POWER"GND";
"A"7;
%"Q_CAP"
"1","(-4350,1000)","0","pure_quanta","I286";
;
LOCATION"PC78"
$SEC"1"
CDS_SEC"1"
PACK_TYPE"0402"
TOLERANCE"10%"
MATERIAL"X7R"
VALUE"470PF"
PART_NUMBER"TMP_QCH14706KB18"
VOLTAGE"50V"
CDS_LIB"pure_quanta";
"B"
$PN"2"7;
"A"
$PN"1"76;
%"UNIVERSAL_GND"
"1","(-6525,6100)","1","pure_quanta_power","I311";
;
CDS_LIB"pure_quanta_power"
HDL_POWER"GND";
"A"8;
%"UNIVERSAL_GND"
"1","(-6525,6525)","1","pure_quanta_power","I312";
;
CDS_LIB"pure_quanta_power"
HDL_POWER"GND";
"A"9;
%"Q_CAP"
"1","(-4350,5725)","0","pure_quanta","I319";
;
LOCATION"PC76"
$SEC"1"
CDS_SEC"1"
PART_NUMBER"CH6101MEB01"
PACK_TYPE"C0402"
VOLTAGE"6.3V"
MATERIAL"X6S"
TOLERANCE"20%"
VALUE"10UF"
CDS_LIB"pure_quanta";
"B"
$PN"2"15;
"A"
$PN"1"74;
%"Q_CAP"
"1","(-4350,6200)","0","pure_quanta","I322";
;
LOCATION"PC75"
$SEC"1"
CDS_SEC"1"
MATERIAL"X6S"
TOLERANCE"10%"
VALUE"1UF"
PART_NUMBER"CH5103KEB01"
VOLTAGE"16V"
PACK_TYPE"C0402"
CDS_LIB"pure_quanta";
"B"
$PN"2"14;
"A"
$PN"1"75;
%"Q_RES"
"1","(-3900,6375)","0","pure_quanta","I325";
;
LOCATION"PR76"
$SEC"1"
CDS_SEC"1"
WATTAGE"1/16W"
MATERIAL"CHIP"
TOLERANCE"1%"
VALUE"1"
PART_NUMBER"CS-1002FB23"
PACK_TYPE"0402LF"
CDS_LIB"pure_quanta";
"B"
$PN"2"86;
"A"
$PN"1"75;
%"VCC_CORE"
"1","(-3375,6500)","0","pure_quanta_power","I326";
;
HDL_POWER"P3V3_STBY"
CDS_LIB"pure_quanta_power";
"A"86;
%"RAA229620GNPHA0"
"1","(-5700,3625)","0","pure_quanta","I339";
;
LOCATION"PU12"
$SEC"1"
CDS_SEC"1"
VALUE"RAA229620GNP#HA0"
PART_NUMBER"AR0T6GPV005"
MATERIAL"IC"
PART_TYPE"SMLF"
CDS_LMAN_SYM_OUTLINE"-550,2850,500,-2850"
NEEDS_NO_SIZE"TRUE"
CDS_LIB"pure_quanta";
"CS10"
$PN"28"40;
"PWM10"
$PN"11"50;
"CS9"
$PN"29"53;
"PWM9"
$PN"10"81;
"CS8"
$PN"30"82;
"PWM8"
$PN"9"62;
"CS7"
$PN"31"33;
"PWM7"
$PN"8"83;
"CS0"
$PN"38"78;
"PWM0"
$PN"1"77;
"TEMP1"
$PN"43"61;
"EN1||ADDR_CFG"
$PN"42"59;
"TH_GND"
$PN"TH"27;
"OCP_L \B"
$PN"41"64;
"CS2"
$PN"36"87;
"PWM2"
$PN"3"49;
"CS3"
$PN"35"44;
"PWM3"
$PN"4"42;
"PWM11"
$PN"12"52;
"CS1"
$PN"37"80;
"RGND1"
$PN"39"94;
"VSEN1"
$PN"40"48;
"VDDIO"
$PN"19"58;
"TEMP0"
$PN"44"76;
"VINSEN"
$PN"46"26;
"VMON||IINSEN"
$PN"45"28;
"VCCS"
$PN"48"74;
"PWM6"
$PN"7"84;
"PG0"
$PN"16"39;
"PWM1"
$PN"2"79;
"VSEN0"
$PN"25"73;
"PWM5"
$PN"6"45;
"PWM4"
$PN"5"89;
"PMSDA"
$PN"13"47;
"RGND0"
$PN"26"92;
"EN0"
$PN"17"38;
"NPMALERT \B"
$PN"15"21;
"SVD"
$PN"21"36;
"PG1"
$PN"20"29;
"CS4"
$PN"34"43;
"CS5"
$PN"33"88;
"RESET_L \B"
$PN"18"60;
"SVTO"
$PN"23"46;
"CS6"
$PN"32"85;
"SVC"
$PN"22"37;
"PMSCL"
$PN"14"24;
"SVTI"
$PN"24"41;
"VCC"
$PN"47"75;
"CS11"
$PN"27"51;
%"Q_RES"
"1","(-8075,5625)","0","pure_quanta","I348";
;
LOCATION"PR61"
$SEC"1"
CDS_SEC"1"
PACK_TYPE"0402LF"
PART_NUMBER"CS00002JB38"
MATERIAL"CHIP"
WATTAGE"1/16W"
TOLERANCE"5%"
VALUE"0"
CDS_LIB"pure_quanta";
"B"
$PN"2"46;
"A"
$PN"1"68;
%"Q_RES"
"1","(-8075,5475)","0","pure_quanta","I351";
;
LOCATION"PR62"
$SEC"1"
CDS_SEC"1"
TOLERANCE"5%"
PACK_TYPE"0402LF"
WATTAGE"1/16W"
MATERIAL"CHIP"
VALUE"0"
PART_NUMBER"CS00002JB38"
CDS_LIB"pure_quanta";
"B"
$PN"2"41;
"A"
$PN"1"66;
%"Q_RES"
"1","(-7350,5075)","0","pure_quanta","I366";
;
LOCATION"PR72"
$SEC"1"
CDS_SEC"1"
MATERIAL"CHIP"
TOLERANCE"5%"
VALUE"0"
PACK_TYPE"0402LF"
WATTAGE"1/16W"
PART_NUMBER"CS00002JB38"
CDS_LIB"pure_quanta";
"B"
$PN"2"47;
"A"
$PN"1"25;
%"Q_RES"
"1","(-7350,4925)","0","pure_quanta","I367";
;
LOCATION"PR73"
$SEC"1"
CDS_SEC"1"
VALUE"0"
PACK_TYPE"0402LF"
TOLERANCE"5%"
WATTAGE"1/16W"
MATERIAL"CHIP"
PART_NUMBER"CS00002JB38"
CDS_LIB"pure_quanta";
"B"
$PN"2"21;
"A"
$PN"1"35;
%"Q_RES"
"1","(-7325,2375)","0","pure_quanta","I372";
;
LOCATION"PR64"
$SEC"1"
CDS_SEC"1"
TOLERANCE"5%"
WATTAGE"1/16W"
PART_NUMBER"CS00002JB38"
MATERIAL"CHIP"
VALUE"0"
PACK_TYPE"0402LF"
CDS_LIB"pure_quanta";
"B"
$PN"2"64;
"A"
$PN"1"63;
%"Q_RES"
"1","(-7475,2675)","0","pure_quanta","I378";
;
LOCATION"PR70"
$SEC"1"
CDS_SEC"1"
WATTAGE"1/16W"
MATERIAL"CHIP"
TOLERANCE"1%"
VALUE"1K"
PART_NUMBER"TMP_QCS21002FB24"
PACK_TYPE"0402LF"
CDS_LIB"pure_quanta";
"B"
$PN"2"60;
"A"
$PN"1"56;
%"Q_RES"
"1","(-7325,2525)","0","pure_quanta","I379";
;
LOCATION"PR63"
$SEC"1"
CDS_SEC"1"
PACK_TYPE"0402LF"
WATTAGE"1/16W"
MATERIAL"CHIP"
TOLERANCE"5%"
VALUE"0"
PART_NUMBER"CS00002JB38"
CDS_LIB"pure_quanta";
"B"
$PN"2"60;
"A"
$PN"1"57;
%"Q_CAP"
"2","(-7025,2000)","0","pure_quanta","I380";
;
LOCATION"PC73"
$SEC"1"
CDS_SEC"1"
VALUE"1UF"
MATERIAL"X7R"
TOLERANCE"10%"
PART_NUMBER"CH5101K1B01"
VOLTAGE"6.3V"
PACK_TYPE"0402"
CDS_LIB"pure_quanta";
"A"
$PN"1"58;
"B"
$PN"2"10;
%"UNIVERSAL_GND"
"1","(-6625,2000)","1","pure_quanta_power","I381";
;
CDS_LIB"pure_quanta_power"
HDL_POWER"GND";
"A"10;
%"VCC_CORE"
"1","(-7575,2075)","0","pure_quanta_power","I382";
;
HDL_POWER"PVDD18_S5_P0"
CDS_LIB"pure_quanta_power";
"A"58;
%"Q_RES"
"1","(-6775,2250)","0","pure_quanta","I385";
;
LOCATION"PR75"
$SEC"1"
CDS_SEC"1"
PART_NUMBER"TMP_QCS21002FB24"
WATTAGE"1/16W"
MATERIAL"CHIP"
TOLERANCE"1%"
VALUE"1K"
PACK_TYPE"0402LF"
CDS_LIB"pure_quanta";
"B"
$PN"2"64;
"A"
$PN"1"58;
%"VCC_CORE"
"1","(-9200,2650)","0","pure_quanta_power","I390";
;
HDL_POWER"P3V3_STBY"
CDS_LIB"pure_quanta_power";
"A"55;
%"MOSFET_N"
"1","(-9250,1825)","0","pure_quanta","I391";
;
LOCATION"PQ14"
$SEC"1"
CDS_SEC"1"
PART_NUMBER"BAM138K0000"
VALUE"BSS138K"
MATERIAL"IC"
MANUF_PN"BSS138K"
CDS_LIB"pure_quanta"
CDS_LMAN_SYM_OUTLINE"-50,50,100,-150"
PACK_TYPE"SMLF";
"GATE"
$PN"G"32;
"SOURCE"
$PN"S"54;
"DRAIN"
$PN"D"65;
%"Q_RES"
"2","(-9200,2350)","0","pure_quanta","I392";
;
LOCATION"PR55"
$SEC"1"
CDS_SEC"1"
WATTAGE"1/16W"
MATERIAL"CHIP"
TOLERANCE"1%"
VALUE"1K"
PACK_TYPE"0402LF"
CDS_LIB"pure_quanta"
PART_NUMBER"TMP_QCS21002FB24";
"A"
$PN"1"55;
"B"
$PN"2"65;
%"UNIVERSAL_GND"
"1","(-9200,1450)","0","pure_quanta_power","I393";
;
CDS_LIB"pure_quanta_power"
HDL_POWER"GND";
"A"54;
%"Q_RES"
"2","(-8550,1675)","0","pure_quanta","I394";
;
LOCATION"PR67"
$SEC"1"
CDS_SEC"1"
PART_NUMBER"CS21962FB08"
WATTAGE"1/16W"
MATERIAL"CHIP"
TOLERANCE"1%"
VALUE"1.96K"
PACK_TYPE"0402LF"
CDS_LIB"pure_quanta";
"A"
$PN"1"59;
"B"
$PN"2"54;
%"Q_RES"
"1","(-9950,1725)","0","pure_quanta","I395";
;
LOCATION"PR47"
$SEC"1"
CDS_SEC"1"
WATTAGE"1/16W"
MATERIAL"CHIP"
TOLERANCE"5%"
VALUE"0"
PART_NUMBER"CS00002JB38"
PACK_TYPE"0402LF"
CDS_LIB"pure_quanta";
"B"
$PN"2"32;
"A"
$PN"1"34;
%"Q_CAP"
"1","(-9700,1550)","0","pure_quanta","I397";
;
LOCATION"PC66"
$SEC"1"
CDS_SEC"1"
PART_NUMBER"TMP_QCH21006JB10"
MATERIAL"X7R"
TOLERANCE"5%"
VALUE"1000PF"
VOLTAGE"50V"
PACK_TYPE"0402"
CDS_LIB"pure_quanta";
"B"
$PN"2"11;
"A"
$PN"1"32;
%"UNIVERSAL_GND"
"1","(-9700,1300)","0","pure_quanta_power","I398";
;
CDS_LIB"pure_quanta_power"
HDL_POWER"GND";
"A"11;
%"VCC_CORE"
"1","(-8925,1075)","0","pure_quanta_power","I399";
;
HDL_POWER"P5V_STBY"
CDS_LIB"pure_quanta_power";
"A"12;
%"Q_CAP"
"1","(-4350,1575)","0","pure_quanta","I400";
;
LOCATION"PC77"
$SEC"1"
CDS_SEC"1"
MATERIAL"X7R"
TOLERANCE"10%"
VALUE"470PF"
PART_NUMBER"TMP_QCH14706KB18"
VOLTAGE"50V"
PACK_TYPE"0402"
CDS_LIB"pure_quanta";
"B"
$PN"2"13;
"A"
$PN"1"61;
%"UNIVERSAL_GND"
"1","(-4350,1325)","0","pure_quanta_power","I401";
;
CDS_LIB"pure_quanta_power"
HDL_POWER"GND";
"A"13;
%"Q_RES"
"2","(-9350,6250)","0","pure_quanta","I408";
;
LOCATION"PR48"
$SEC"1"
CDS_SEC"1"
WATTAGE"1/16W"
MATERIAL"EMPTY"
TOLERANCE"1%"
VALUE"1K"
PART_NUMBER"TMP_QCS21002FB24"
PACK_TYPE"0402LF"
CDS_LIB"pure_quanta";
"A"
$PN"1"69;
"B"
$PN"2"37;
%"Q_RES"
"2","(-10150,6250)","0","pure_quanta","I409";
;
LOCATION"PR41"
$SEC"1"
CDS_SEC"1"
WATTAGE"1/16W"
MATERIAL"EMPTY"
TOLERANCE"1%"
VALUE"1K"
PACK_TYPE"0402LF"
CDS_LIB"pure_quanta"
PART_NUMBER"TMP_QCS21002FB24";
"A"
$PN"1"69;
"B"
$PN"2"66;
%"Q_RES"
"2","(-9800,6250)","0","pure_quanta","I410";
;
LOCATION"PR43"
$SEC"1"
CDS_SEC"1"
WATTAGE"1/16W"
MATERIAL"EMPTY"
TOLERANCE"1%"
VALUE"1K"
PACK_TYPE"0402LF"
CDS_LIB"pure_quanta"
PART_NUMBER"TMP_QCS21002FB24";
"A"
$PN"1"69;
"B"
$PN"2"68;
%"Q_RES"
"2","(-9600,6250)","0","pure_quanta","I411";
;
LOCATION"PR45"
$SEC"1"
CDS_SEC"1"
WATTAGE"1/16W"
MATERIAL"EMPTY"
TOLERANCE"1%"
VALUE"1K"
PACK_TYPE"0402LF"
CDS_LIB"pure_quanta"
PART_NUMBER"TMP_QCS21002FB24";
"A"
$PN"1"69;
"B"
$PN"2"36;
%"Q_RES"
"2","(-10025,5275)","0","pure_quanta","I414";
;
LOCATION"PR42"
$SEC"1"
CDS_SEC"1"
WATTAGE"1/16W"
MATERIAL"EMPTY"
TOLERANCE"1%"
VALUE"1K"
PACK_TYPE"0402LF"
CDS_LIB"pure_quanta"
PART_NUMBER"TMP_QCS21002FB24";
"A"
$PN"1"68;
"B"
$PN"2"67;
%"Q_RES"
"2","(-10250,5275)","0","pure_quanta","I415";
;
LOCATION"PR40"
$SEC"1"
CDS_SEC"1"
WATTAGE"1/16W"
MATERIAL"CHIP"
TOLERANCE"5%"
VALUE"1K"
PACK_TYPE"0402LF"
CDS_LIB"pure_quanta"
PART_NUMBER"TMP_QCS21002JB34";
"A"
$PN"1"66;
"B"
$PN"2"67;
%"UNIVERSAL_GND"
"1","(-10250,4825)","0","pure_quanta_power","I416";
;
CDS_LIB"pure_quanta_power"
HDL_POWER"GND";
"A"67;
%"VCC_CORE"
"1","(-10150,6600)","0","pure_quanta_power","I417";
;
HDL_POWER"PVDD18_S5_P0"
CDS_LIB"pure_quanta_power";
"A"69;
%"UNIVERSAL_GND"
"1","(-4350,6000)","0","pure_quanta_power","I418";
;
CDS_LIB"pure_quanta_power"
HDL_POWER"GND";
"A"14;
%"UNIVERSAL_GND"
"1","(-4350,5525)","0","pure_quanta_power","I419";
;
CDS_LIB"pure_quanta_power"
HDL_POWER"GND";
"A"15;
%"VCC_CORE"
"1","(-7925,2800)","0","pure_quanta_power","I423";
;
HDL_POWER"PVDD18_S5_P0"
CDS_LIB"pure_quanta_power";
"A"56;
%"MOSFET_PCH_GDS_ESD_PROTECTED"
"1","(-8575,2150)","6","pure_quanta","I424";
;
LOCATION"PQ10"
$SEC"1"
CDS_SEC"1"
MATERIAL"IC"
VALUE"PJA3415AE"
PART_NUMBER"BAM34150008"
PART_TYPE"SMLF"
CDS_LIB"pure_quanta"
NEEDS_NO_SIZE"TRUE"
CDS_LMAN_SYM_OUTLINE"-125,150,125,-150";
"S"
$PN"S"55;
"G"
$PN"G"65;
"D"
$PN"D"59;
%"UNIVERSAL_GND"
"1","(-4675,5525)","0","pure_quanta_power","I425";
;
CDS_LIB"pure_quanta_power"
HDL_POWER"GND";
"A"16;
%"Q_CAP"
"1","(-4675,5750)","0","pure_quanta","I426";
;
LOCATION"PC15"
$SEC"1"
CDS_SEC"1"
TOLERANCE"10%"
VALUE"0.1UF"
MATERIAL"X7R"
PART_NUMBER"CH4104K1B00"
VOLTAGE"25V"
PACK_TYPE"0402"
CDS_LIB"pure_quanta";
"B"
$PN"2"16;
"A"
$PN"1"74;
%"UNIVERSAL_GND"
"1","(-4675,6000)","0","pure_quanta_power","I427";
;
CDS_LIB"pure_quanta_power"
HDL_POWER"GND";
"A"17;
%"Q_CAP"
"1","(-4675,6225)","0","pure_quanta","I428";
;
LOCATION"PC14"
$SEC"1"
CDS_SEC"1"
MATERIAL"X7R"
TOLERANCE"10%"
VALUE"0.1UF"
PART_NUMBER"CH4104K1B00"
VOLTAGE"25V"
PACK_TYPE"0402"
CDS_LIB"pure_quanta";
"B"
$PN"2"17;
"A"
$PN"1"75;
%"Q_CAP"
"1","(-9425,5275)","0","pure_quanta","I465";
;
LOCATION"PC305"
$SEC"1"
CDS_SEC"1"
MATERIAL"EMPTY"
TOLERANCE"5%"
VALUE"10PF"
PART_NUMBER"CH01006JB08"
VOLTAGE"50V"
PACK_TYPE"0402"
CDS_LIB"pure_quanta";
"B"
$PN"2"67;
"A"
$PN"1"37;
%"Q_CAP"
"1","(-9675,5275)","0","pure_quanta","I466";
;
LOCATION"PC304"
$SEC"1"
CDS_SEC"1"
MATERIAL"EMPTY"
TOLERANCE"5%"
VALUE"10PF"
PART_NUMBER"CH01006JB08"
VOLTAGE"50V"
PACK_TYPE"0402"
CDS_LIB"pure_quanta";
"B"
$PN"2"67;
"A"
$PN"1"36;
%"Q_CAP"
"1","(-9850,5275)","0","pure_quanta","I467";
;
LOCATION"PC303"
$SEC"1"
CDS_SEC"1"
MATERIAL"EMPTY"
TOLERANCE"5%"
VALUE"10PF"
PART_NUMBER"CH01006JB08"
VOLTAGE"50V"
PACK_TYPE"0402"
CDS_LIB"pure_quanta";
"B"
$PN"2"67;
"A"
$PN"1"68;
%"UNIVERSAL_GND"
"1","(-3825,3100)","0","pure_quanta_power","I484";
;
CDS_LIB"pure_quanta_power"
HDL_POWER"GND";
"A"18;
%"Q_RES"
"1","(-4275,3175)","0","pure_quanta","I485";
;
LOCATION"PR32"
$SEC"1"
CDS_SEC"1"
PART_NUMBER"CS00002JB38"
PACK_TYPE"0402LF"
WATTAGE"1/16W"
MATERIAL"CHIP"
TOLERANCE"5%"
VALUE"0"
CDS_LIB"pure_quanta";
"B"
$PN"2"18;
"A"
$PN"1"43;
%"UNIVERSAL_GND"
"1","(-3825,3400)","0","pure_quanta_power","I490";
;
CDS_LIB"pure_quanta_power"
HDL_POWER"GND";
"A"19;
%"Q_RES"
"1","(-4275,3475)","0","pure_quanta","I491";
;
LOCATION"PR532"
$SEC"1"
CDS_SEC"1"
WATTAGE"1/16W"
TOLERANCE"5%"
VALUE"0"
PART_NUMBER"CS00002JB38"
PACK_TYPE"0402LF"
MATERIAL"CHIP"
CDS_LIB"pure_quanta";
"B"
$PN"2"19;
"A"
$PN"1"88;
%"Q_RES"
"2","(-7000,650)","0","pure_quanta","I492";
;
LOCATION"PR600"
$SEC"1"
CDS_SEC"1"
PART_NUMBER"CS24992FB07"
WATTAGE"1/16W"
MATERIAL"EMPTY"
TOLERANCE"1%"
VALUE"4.99K"
PACK_TYPE"0402LF"
CDS_LIB"pure_quanta";
"A"
$PN"1"26;
"B"
$PN"2"20;
%"UNIVERSAL_GND"
"1","(-7000,450)","0","pure_quanta_power","I493";
;
CDS_LIB"pure_quanta_power"
HDL_POWER"GND";
"A"20;
END.
